# S9S_MB_2U (Grand Teton) — schematic netlist excerpt (pin names and nets, part order shuffled) for the footprints in the layout excerpt that follows; sources: Cadence DE-HDL packaged netlist, KiCad conversion of 03242023_DA0F0TMBIJ0_F0T_Motherboard_J_brd_V01_OCP.brd

R1462  Q_RES  1K 1% CHIP  pkg 0402LF  page 208 : A = PD_CK440_SBI_CLK ; B = GND
R1650  Q_RES  0 5% CHIP  pkg 0402LF  page 262 : A = PWRGD_P1V05_PCH_AUX_R ; B = PWRGD_P1V05_PCH_AUX

(kicad_pcb
	(version 20260206)
	(generator "pcbnew")
	(generator_version "10.0")
	(general
		(thickness 1.6)
		(legacy_teardrops no)
	)
	(paper "A4")
	(title_block
		(title "03242023_DA0F0TMBIJ0_F0T_Motherboard_J_brd_V01_OCP.brd")
		(comment 1 "Grand Teton / footprints 4952-4953 of 6105")
	)
	(layers
		(0 "F.Cu" signal "TOP")
		(4 "In1.Cu" signal "GND")
		(6 "In2.Cu" signal "IN1")
		(8 "In3.Cu" signal "GND1")
		(10 "In4.Cu" signal "IN2")
		(12 "In5.Cu" signal "GND2")
		(14 "In6.Cu" signal "IN3")
		(16 "In7.Cu" signal "GND3")
		(18 "In8.Cu" signal "VCC")
		(20 "In9.Cu" signal "VCC1")
		(22 "In10.Cu" signal "GND4")
		(24 "In11.Cu" signal "IN4")
		(26 "In12.Cu" signal "GND5")
		(28 "In13.Cu" signal "IN5")
		(30 "In14.Cu" signal "GND6")
		(32 "In15.Cu" signal "IN6")
		(34 "In16.Cu" signal "GND7")
		(2 "B.Cu" signal "BOTTOM")
		(9 "F.Adhes" user "F.Adhesive")
		(11 "B.Adhes" user "B.Adhesive")
		(13 "F.Paste" user "Package Geometry/Pastemask Top")
		(15 "B.Paste" user "Package Geometry/Pastemask Bottom")
		(5 "F.SilkS" user "Ref Des/Silkscreen Top")
		(7 "B.SilkS" user "Ref Des/Silkscreen Bottom")
		(1 "F.Mask" user "Board Geometry/Soldermask Top")
		(3 "B.Mask" user "Board Geometry/Soldermask Bottom")
		(17 "Dwgs.User" user "User.Drawings")
		(19 "Cmts.User" user "User.Comments")
		(21 "Eco1.User" user "User.Eco1")
		(23 "Eco2.User" user "User.Eco2")
		(25 "Edge.Cuts" user "Board Geometry/Outline")
		(27 "Margin" user)
		(31 "F.CrtYd" user "Package Geometry/Place Bound Top")
		(29 "B.CrtYd" user "Package Geometry/Place Bound Bottom")
		(35 "F.Fab" user "Ref Des/Assembly Top")
		(33 "B.Fab" user "Ref Des/Assembly Bottom")
	)
	(footprint ""
		(layer "B.Cu")
		(at 257.287268 -75.32878 90)
		(property "Reference" "R1650"
			(at 0 0 90)
			(layer "B.SilkS")
			(hide yes)
			(effects
				(font
					(size 1.27 1.27)
				)
				(justify mirror)
			)
		)
		(property "Value" ""
			(at 0 0 90)
			(layer "B.Fab")
			(effects
				(font
					(size 1.27 1.27)
				)
				(justify mirror)
			)
		)
		(duplicate_pad_numbers_are_jumpers no)
		(fp_line
			(start 0.7874 -0.4064)
			(end -0.7874 -0.4064)
			(stroke
				(width 0.1524)
				(type default)
			)
			(layer "B.SilkS")
		)
		(fp_line
			(start -0.7874 -0.4064)
			(end -0.7874 0.4064)
			(stroke
				(width 0.1524)
				(type default)
			)
			(layer "B.SilkS")
		)
		(fp_line
			(start 0.7874 0.4064)
			(end 0.7874 -0.4064)
			(stroke
				(width 0.1524)
				(type default)
			)
			(layer "B.SilkS")
		)
		(fp_line
			(start -0.7874 0.4064)
			(end 0.7874 0.4064)
			(stroke
				(width 0.1524)
				(type default)
			)
			(layer "B.SilkS")
		)
		(fp_line
			(start 0.67945 -0.305054)
			(end 0.12065 -0.305054)
			(stroke
				(width 0.1)
				(type default)
			)
			(layer "B.Fab")
		)
		(fp_line
			(start 0.12065 -0.305054)
			(end 0.12065 -0.2794)
			(stroke
				(width 0.1)
				(type default)
			)
			(layer "B.Fab")
		)
		(fp_line
			(start -0.12065 -0.3048)
			(end -0.67945 -0.3048)
			(stroke
				(width 0.1)
				(type default)
			)
			(layer "B.Fab")
		)
		(fp_line
			(start -0.67945 -0.3048)
			(end -0.67945 0.3048)
			(stroke
				(width 0.1)
				(type default)
			)
			(layer "B.Fab")
		)
		(fp_line
			(start 0.12065 -0.2794)
			(end -0.12065 -0.2794)
			(stroke
				(width 0.1)
				(type default)
			)
			(layer "B.Fab")
		)
		(fp_line
			(start -0.12065 -0.2794)
			(end -0.12065 -0.3048)
			(stroke
				(width 0.1)
				(type default)
			)
			(layer "B.Fab")
		)
		(fp_line
			(start 0.12065 0.2794)
			(end 0.12065 0.3048)
			(stroke
				(width 0.1)
				(type default)
			)
			(layer "B.Fab")
		)
		(fp_line
			(start -0.120396 0.2794)
			(end 0.12065 0.2794)
			(stroke
				(width 0.1)
				(type default)
			)
			(layer "B.Fab")
		)
		(fp_line
			(start 0.67945 0.3048)
			(end 0.67945 -0.305054)
			(stroke
				(width 0.1)
				(type default)
			)
			(layer "B.Fab")
		)
		(fp_line
			(start 0.12065 0.3048)
			(end 0.67945 0.3048)
			(stroke
				(width 0.1)
				(type default)
			)
			(layer "B.Fab")
		)
		(fp_line
			(start -0.120396 0.3048)
			(end -0.120396 0.2794)
			(stroke
				(width 0.1)
				(type default)
			)
			(layer "B.Fab")
		)
		(fp_line
			(start -0.67945 0.3048)
			(end -0.120396 0.3048)
			(stroke
				(width 0.1)
				(type default)
			)
			(layer "B.Fab")
		)
		(pad "1" smd circle
			(at 0.40005 0 270)
			(size 0 0)
			(layers "B.Cu" "B.Mask" "B.Paste")
			(net "PWRGD_P1V05_PCH_AUX_R")
		)
		(pad "2" smd circle
			(at -0.40005 0 270)
			(size 0 0)
			(layers "B.Cu" "B.Mask" "B.Paste")
			(net "PWRGD_P1V05_PCH_AUX")
		)
	)
	(footprint ""
		(layer "B.Cu")
		(at 251.175266 -107.178094)
		(property "Reference" "R1462"
			(at 0 0 0)
			(layer "B.SilkS")
			(hide yes)
			(effects
				(font
					(size 1.27 1.27)
				)
				(justify mirror)
			)
		)
		(property "Value" ""
			(at 0 0 0)
			(layer "B.Fab")
			(effects
				(font
					(size 1.27 1.27)
				)
				(justify mirror)
			)
		)
		(duplicate_pad_numbers_are_jumpers no)
		(fp_line
			(start -0.7874 -0.4064)
			(end -0.7874 0.4064)
			(stroke
				(width 0.1524)
				(type default)
			)
			(layer "B.SilkS")
		)
		(fp_line
			(start -0.7874 0.4064)
			(end 0.7874 0.4064)
			(stroke
				(width 0.1524)
				(type default)
			)
			(layer "B.SilkS")
		)
		(fp_line
			(start 0.7874 -0.4064)
			(end -0.7874 -0.4064)
			(stroke
				(width 0.1524)
				(type default)
			)
			(layer "B.SilkS")
		)
		(fp_line
			(start 0.7874 0.4064)
			(end 0.7874 -0.4064)
			(stroke
				(width 0.1524)
				(type default)
			)
			(layer "B.SilkS")
		)
		(fp_line
			(start -0.67945 -0.3048)
			(end -0.67945 0.3048)
			(stroke
				(width 0.1)
				(type default)
			)
			(layer "B.Fab")
		)
		(fp_line
			(start -0.67945 0.3048)
			(end -0.120396 0.3048)
			(stroke
				(width 0.1)
				(type default)
			)
			(layer "B.Fab")
		)
		(fp_line
			(start -0.12065 -0.3048)
			(end -0.67945 -0.3048)
			(stroke
				(width 0.1)
				(type default)
			)
			(layer "B.Fab")
		)
		(fp_line
			(start -0.12065 -0.2794)
			(end -0.12065 -0.3048)
			(stroke
				(width 0.1)
				(type default)
			)
			(layer "B.Fab")
		)
		(fp_line
			(start -0.120396 0.2794)
			(end 0.12065 0.2794)
			(stroke
				(width 0.1)
				(type default)
			)
			(layer "B.Fab")
		)
		(fp_line
			(start -0.120396 0.3048)
			(end -0.120396 0.2794)
			(stroke
				(width 0.1)
				(type default)
			)
			(layer "B.Fab")
		)
		(fp_line
			(start 0.12065 -0.305054)
			(end 0.12065 -0.2794)
			(stroke
				(width 0.1)
				(type default)
			)
			(layer "B.Fab")
		)
		(fp_line
			(start 0.12065 -0.2794)
			(end -0.12065 -0.2794)
			(stroke
				(width 0.1)
				(type default)
			)
			(layer "B.Fab")
		)
		(fp_line
			(start 0.12065 0.2794)
			(end 0.12065 0.3048)
			(stroke
				(width 0.1)
				(type default)
			)
			(layer "B.Fab")
		)
		(fp_line
			(start 0.12065 0.3048)
			(end 0.67945 0.3048)
			(stroke
				(width 0.1)
				(type default)
			)
			(layer "B.Fab")
		)
		(fp_line
			(start 0.67945 -0.305054)
			(end 0.12065 -0.305054)
			(stroke
				(width 0.1)
				(type default)
			)
			(layer "B.Fab")
		)
		(fp_line
			(start 0.67945 0.3048)
			(end 0.67945 -0.305054)
			(stroke
				(width 0.1)
				(type default)
			)
			(layer "B.Fab")
		)
		(pad "1" smd circle
			(at 0.40005 0 180)
			(size 0 0)
			(layers "B.Cu" "B.Mask" "B.Paste")
			(net "PD_CK440_SBI_CLK")
		)
		(pad "2" smd circle
			(at -0.40005 0 180)
			(size 0 0)
			(layers "B.Cu" "B.Mask" "B.Paste")
			(net "GND")
		)
	)
)
